(kicad_pcb
	(version 20260206)
	(generator "pcbnew")
	(generator_version "10.0")
	(general
		(thickness 1.6)
		(legacy_teardrops no)
	)
	(paper "A4")
	(title_block
		(title "Wiwynn_Tioga_Pass_MB.brd")
		(comment 1 "Tioga Pass / footprints 3003-3009 of 4770")
	)
	(layers
		(0 "F.Cu" signal "TOP")
		(4 "In1.Cu" signal "L2GND")
		(6 "In2.Cu" signal "L3")
		(8 "In3.Cu" signal "L4GND")
		(10 "In4.Cu" signal "L5")
		(12 "In5.Cu" signal "L6GND")
		(14 "In6.Cu" signal "L7VCC")
		(16 "In7.Cu" signal "L8VCC")
		(18 "In8.Cu" signal "L9GND")
		(20 "In9.Cu" signal "L10")
		(22 "In10.Cu" signal "L11GND")
		(24 "In11.Cu" signal "L12")
		(26 "In12.Cu" signal "L13GND")
		(2 "B.Cu" signal "BOTTOM")
		(9 "F.Adhes" user "F.Adhesive")
		(11 "B.Adhes" user "B.Adhesive")
		(13 "F.Paste" user "Package Geometry/Pastemask Top")
		(15 "B.Paste" user "Package Geometry/Pastemask Bottom")
		(5 "F.SilkS" user "Ref Des/Silkscreen Top")
		(7 "B.SilkS" user "Ref Des/Silkscreen Bottom")
		(1 "F.Mask" user "Board Geometry/Soldermask Top")
		(3 "B.Mask" user "Board Geometry/Soldermask Bottom")
		(17 "Dwgs.User" user "User.Drawings")
		(19 "Cmts.User" user "User.Comments")
		(21 "Eco1.User" user "User.Eco1")
		(23 "Eco2.User" user "User.Eco2")
		(25 "Edge.Cuts" user "Board Geometry/Outline")
		(27 "Margin" user)
		(31 "F.CrtYd" user "Package Geometry/Place Bound Top")
		(29 "B.CrtYd" user "Package Geometry/Place Bound Bottom")
		(35 "F.Fab" user "Ref Des/Assembly Top")
		(33 "B.Fab" user "Ref Des/Assembly Bottom")
	)
	(footprint ""
		(layer "B.Cu")
		(at 348.361 -133.604 180)
		(property "Reference" "C3M9"
			(at 0 0 0)
			(layer "B.SilkS")
			(hide yes)
			(effects
				(font
					(size 1.27 1.27)
				)
				(justify mirror)
			)
		)
		(property "Value" ""
			(at 0 0 0)
			(layer "B.Fab")
			(effects
				(font
					(size 1.27 1.27)
				)
				(justify mirror)
			)
		)
		(duplicate_pad_numbers_are_jumpers no)
		(fp_poly
			(pts
				(xy -0.3048 -0.1016) (xy -0.3048 0.9906) (xy 0.3048 0.9906) (xy 0.3048 -0.1016)
			)
			(stroke
				(width 0)
				(type default)
			)
			(fill no)
			(layer "B.CrtYd")
		)
		(fp_line
			(start 0.3048 0.9906)
			(end -0.3048 0.9906)
			(stroke
				(width 0.1)
				(type default)
			)
			(layer "B.Fab")
		)
		(fp_line
			(start 0.3048 -0.1016)
			(end 0.3048 0.9906)
			(stroke
				(width 0.1)
				(type default)
			)
			(layer "B.Fab")
		)
		(fp_line
			(start -0.3048 0.9906)
			(end -0.3048 -0.1016)
			(stroke
				(width 0.1)
				(type default)
			)
			(layer "B.Fab")
		)
		(fp_line
			(start -0.3048 -0.1016)
			(end 0.3048 -0.1016)
			(stroke
				(width 0.1)
				(type default)
			)
			(layer "B.Fab")
		)
		(pad "1" smd rect
			(at 0 0)
			(size 0.508 0.508)
			(layers "B.Cu" "B.Mask" "B.Paste")
			(net "VR_FET_SW_P12V_STBY_PVPP_DEF")
		)
		(pad "2" smd rect
			(at 0 0.889)
			(size 0.508 0.508)
			(layers "B.Cu" "B.Mask" "B.Paste")
			(net "GND")
		)
		(zone
			(layer "B.Cu")
			(hatch none 0.5)
			(connect_pads
				(clearance 0)
			)
			(min_thickness 0.25)
			(keepout
				(tracks not_allowed)
				(vias allowed)
				(pads allowed)
				(copperpour not_allowed)
				(footprints allowed)
			)
			(placement
				(enabled no)
				(sheetname "")
			)
			(fill
				(thermal_gap 0.5)
				(thermal_bridge_width 0.5)
				(island_removal_mode 0)
			)
			(polygon
				(pts
					(xy 348.107 -134.239) (xy 348.615 -134.239) (xy 348.615 -133.858) (xy 348.107 -133.858)
				)
			)
		)
		(zone
			(layer "B.Cu")
			(hatch none 0.5)
			(connect_pads
				(clearance 0)
			)
			(min_thickness 0.25)
			(keepout
				(tracks allowed)
				(vias not_allowed)
				(pads allowed)
				(copperpour not_allowed)
				(footprints allowed)
			)
			(placement
				(enabled no)
				(sheetname "")
			)
			(fill
				(thermal_gap 0.5)
				(thermal_bridge_width 0.5)
				(island_removal_mode 0)
			)
			(polygon
				(pts
					(xy 348.107 -133.858) (xy 348.615 -133.858) (xy 348.615 -134.239) (xy 348.107 -134.239)
				)
			)
		)
	)
	(footprint ""
		(layer "B.Cu")
		(at 450.98335 -52.407058)
		(property "Reference" "C1R9"
			(at 0 0 0)
			(layer "B.SilkS")
			(hide yes)
			(effects
				(font
					(size 1.27 1.27)
				)
				(justify mirror)
			)
		)
		(property "Value" ""
			(at 0 0 0)
			(layer "B.Fab")
			(effects
				(font
					(size 1.27 1.27)
				)
				(justify mirror)
			)
		)
		(duplicate_pad_numbers_are_jumpers no)
		(fp_poly
			(pts
				(xy -0.3048 -0.1016) (xy -0.3048 0.9906) (xy 0.3048 0.9906) (xy 0.3048 -0.1016)
			)
			(stroke
				(width 0)
				(type default)
			)
			(fill no)
			(layer "B.CrtYd")
		)
		(fp_line
			(start -0.3048 -0.1016)
			(end 0.3048 -0.1016)
			(stroke
				(width 0.1)
				(type default)
			)
			(layer "B.Fab")
		)
		(fp_line
			(start -0.3048 0.9906)
			(end -0.3048 -0.1016)
			(stroke
				(width 0.1)
				(type default)
			)
			(layer "B.Fab")
		)
		(fp_line
			(start 0.3048 -0.1016)
			(end 0.3048 0.9906)
			(stroke
				(width 0.1)
				(type default)
			)
			(layer "B.Fab")
		)
		(fp_line
			(start 0.3048 0.9906)
			(end -0.3048 0.9906)
			(stroke
				(width 0.1)
				(type default)
			)
			(layer "B.Fab")
		)
		(pad "1" smd rect
			(at 0 0 180)
			(size 0.508 0.508)
			(layers "B.Cu" "B.Mask" "B.Paste")
			(net "P3E_CPU0_PE3_OCP_TXN<4>")
		)
		(pad "2" smd rect
			(at 0 0.889 180)
			(size 0.508 0.508)
			(layers "B.Cu" "B.Mask" "B.Paste")
			(net "P3E_OCP_CPU0_PE3_C_TXN<4>")
		)
		(zone
			(layer "B.Cu")
			(hatch none 0.5)
			(connect_pads
				(clearance 0)
			)
			(min_thickness 0.25)
			(keepout
				(tracks allowed)
				(vias not_allowed)
				(pads allowed)
				(copperpour not_allowed)
				(footprints allowed)
			)
			(placement
				(enabled no)
				(sheetname "")
			)
			(fill
				(thermal_gap 0.5)
				(thermal_bridge_width 0.5)
				(island_removal_mode 0)
			)
			(polygon
				(pts
					(xy 451.23735 -52.153058) (xy 450.72935 -52.153058) (xy 450.72935 -51.772058) (xy 451.23735 -51.772058)
				)
			)
		)
		(zone
			(layer "B.Cu")
			(hatch none 0.5)
			(connect_pads
				(clearance 0)
			)
			(min_thickness 0.25)
			(keepout
				(tracks not_allowed)
				(vias allowed)
				(pads allowed)
				(copperpour not_allowed)
				(footprints allowed)
			)
			(placement
				(enabled no)
				(sheetname "")
			)
			(fill
				(thermal_gap 0.5)
				(thermal_bridge_width 0.5)
				(island_removal_mode 0)
			)
			(polygon
				(pts
					(xy 451.23735 -51.772058) (xy 450.72935 -51.772058) (xy 450.72935 -52.153058) (xy 451.23735 -52.153058)
				)
			)
		)
	)
	(footprint ""
		(layer "B.Cu")
		(at 354.543614 -122.662442 -90)
		(property "Reference" "C3M3"
			(at 0 0 90)
			(layer "B.SilkS")
			(hide yes)
			(effects
				(font
					(size 1.27 1.27)
				)
				(justify mirror)
			)
		)
		(property "Value" ""
			(at 0 0 90)
			(layer "B.Fab")
			(effects
				(font
					(size 1.27 1.27)
				)
				(justify mirror)
			)
		)
		(duplicate_pad_numbers_are_jumpers no)
		(fp_poly
			(pts
				(xy -0.3048 -0.1016) (xy -0.3048 0.9906) (xy 0.3048 0.9906) (xy 0.3048 -0.1016)
			)
			(stroke
				(width 0)
				(type default)
			)
			(fill no)
			(layer "B.CrtYd")
		)
		(fp_line
			(start -0.3048 0.9906)
			(end -0.3048 -0.1016)
			(stroke
				(width 0.1)
				(type default)
			)
			(layer "B.Fab")
		)
		(fp_line
			(start 0.3048 0.9906)
			(end -0.3048 0.9906)
			(stroke
				(width 0.1)
				(type default)
			)
			(layer "B.Fab")
		)
		(fp_line
			(start -0.3048 -0.1016)
			(end 0.3048 -0.1016)
			(stroke
				(width 0.1)
				(type default)
			)
			(layer "B.Fab")
		)
		(fp_line
			(start 0.3048 -0.1016)
			(end 0.3048 0.9906)
			(stroke
				(width 0.1)
				(type default)
			)
			(layer "B.Fab")
		)
		(pad "1" smd rect
			(at 0 0 90)
			(size 0.508 0.508)
			(layers "B.Cu" "B.Mask" "B.Paste")
			(net "P3E_CPU0_PE1_PCH_R_RXP<12>")
		)
		(pad "2" smd rect
			(at 0 0.889 90)
			(size 0.508 0.508)
			(layers "B.Cu" "B.Mask" "B.Paste")
			(net "P3E_CPU0_PE1_PCH_RXP<12>")
		)
		(zone
			(layer "B.Cu")
			(hatch none 0.5)
			(connect_pads
				(clearance 0)
			)
			(min_thickness 0.25)
			(keepout
				(tracks not_allowed)
				(vias allowed)
				(pads allowed)
				(copperpour not_allowed)
				(footprints allowed)
			)
			(placement
				(enabled no)
				(sheetname "")
			)
			(fill
				(thermal_gap 0.5)
				(thermal_bridge_width 0.5)
				(island_removal_mode 0)
			)
			(polygon
				(pts
					(xy 353.908614 -122.408442) (xy 353.908614 -122.916442) (xy 354.289614 -122.916442) (xy 354.289614 -122.408442)
				)
			)
		)
		(zone
			(layer "B.Cu")
			(hatch none 0.5)
			(connect_pads
				(clearance 0)
			)
			(min_thickness 0.25)
			(keepout
				(tracks allowed)
				(vias not_allowed)
				(pads allowed)
				(copperpour not_allowed)
				(footprints allowed)
			)
			(placement
				(enabled no)
				(sheetname "")
			)
			(fill
				(thermal_gap 0.5)
				(thermal_bridge_width 0.5)
				(island_removal_mode 0)
			)
			(polygon
				(pts
					(xy 354.289614 -122.408442) (xy 354.289614 -122.916442) (xy 353.908614 -122.916442) (xy 353.908614 -122.408442)
				)
			)
		)
	)
	(footprint ""
		(layer "B.Cu")
		(at 100.863654 -77.82814)
		(property "Reference" "C8P17"
			(at 0 0 0)
			(layer "B.SilkS")
			(hide yes)
			(effects
				(font
					(size 1.27 1.27)
				)
				(justify mirror)
			)
		)
		(property "Value" ""
			(at 0 0 0)
			(layer "B.Fab")
			(effects
				(font
					(size 1.27 1.27)
				)
				(justify mirror)
			)
		)
		(duplicate_pad_numbers_are_jumpers no)
		(fp_poly
			(pts
				(xy 0.7239 -0.2159) (xy -0.7239 -0.2159) (xy -0.7239 1.9939) (xy 0.7239 1.9939)
			)
			(stroke
				(width 0)
				(type default)
			)
			(fill no)
			(layer "B.CrtYd")
		)
		(fp_line
			(start -0.7239 -0.2159)
			(end 0.7239 -0.2159)
			(stroke
				(width 0.1)
				(type default)
			)
			(layer "B.Fab")
		)
		(fp_line
			(start -0.7239 1.9939)
			(end -0.7239 -0.2159)
			(stroke
				(width 0.1)
				(type default)
			)
			(layer "B.Fab")
		)
		(fp_line
			(start 0.7239 -0.2159)
			(end 0.7239 1.9939)
			(stroke
				(width 0.1)
				(type default)
			)
			(layer "B.Fab")
		)
		(fp_line
			(start 0.7239 1.9939)
			(end -0.7239 1.9939)
			(stroke
				(width 0.1)
				(type default)
			)
			(layer "B.Fab")
		)
		(pad "1" smd rect
			(at 0 0 180)
			(size 1.27 1.016)
			(layers "B.Cu" "B.Mask" "B.Paste")
			(net "PVCCIN_CPU1")
		)
		(pad "2" smd rect
			(at 0 1.778 180)
			(size 1.27 1.016)
			(layers "B.Cu" "B.Mask" "B.Paste")
			(net "GND")
		)
		(zone
			(layer "B.Cu")
			(hatch none 0.5)
			(connect_pads
				(clearance 0)
			)
			(min_thickness 0.25)
			(keepout
				(tracks not_allowed)
				(vias allowed)
				(pads allowed)
				(copperpour not_allowed)
				(footprints allowed)
			)
			(placement
				(enabled no)
				(sheetname "")
			)
			(fill
				(thermal_gap 0.5)
				(thermal_bridge_width 0.5)
				(island_removal_mode 0)
			)
			(polygon
				(pts
					(xy 101.498654 -77.32014) (xy 100.228654 -77.32014) (xy 100.228654 -76.55814) (xy 101.498654 -76.55814)
				)
			)
		)
	)
	(footprint ""
		(layer "B.Cu")
		(at 359.84688 -77.923136)
		(property "Reference" "C3P38"
			(at 0 0 0)
			(layer "B.SilkS")
			(hide yes)
			(effects
				(font
					(size 1.27 1.27)
				)
				(justify mirror)
			)
		)
		(property "Value" ""
			(at 0 0 0)
			(layer "B.Fab")
			(effects
				(font
					(size 1.27 1.27)
				)
				(justify mirror)
			)
		)
		(duplicate_pad_numbers_are_jumpers no)
		(fp_poly
			(pts
				(xy -0.3048 -0.1016) (xy -0.3048 0.9906) (xy 0.3048 0.9906) (xy 0.3048 -0.1016)
			)
			(stroke
				(width 0)
				(type default)
			)
			(fill no)
			(layer "B.CrtYd")
		)
		(fp_line
			(start -0.3048 -0.1016)
			(end 0.3048 -0.1016)
			(stroke
				(width 0.1)
				(type default)
			)
			(layer "B.Fab")
		)
		(fp_line
			(start -0.3048 0.9906)
			(end -0.3048 -0.1016)
			(stroke
				(width 0.1)
				(type default)
			)
			(layer "B.Fab")
		)
		(fp_line
			(start 0.3048 -0.1016)
			(end 0.3048 0.9906)
			(stroke
				(width 0.1)
				(type default)
			)
			(layer "B.Fab")
		)
		(fp_line
			(start 0.3048 0.9906)
			(end -0.3048 0.9906)
			(stroke
				(width 0.1)
				(type default)
			)
			(layer "B.Fab")
		)
		(pad "1" smd rect
			(at 0 0 180)
			(size 0.508 0.508)
			(layers "B.Cu" "B.Mask" "B.Paste")
			(net "P3E_CPU0_PE1_SS_TXP<7>")
		)
		(pad "2" smd rect
			(at 0 0.889 180)
			(size 0.508 0.508)
			(layers "B.Cu" "B.Mask" "B.Paste")
			(net "P3E_CPU0_PE1_SS_C_TXP<7>")
		)
		(zone
			(layer "B.Cu")
			(hatch none 0.5)
			(connect_pads
				(clearance 0)
			)
			(min_thickness 0.25)
			(keepout
				(tracks allowed)
				(vias not_allowed)
				(pads allowed)
				(copperpour not_allowed)
				(footprints allowed)
			)
			(placement
				(enabled no)
				(sheetname "")
			)
			(fill
				(thermal_gap 0.5)
				(thermal_bridge_width 0.5)
				(island_removal_mode 0)
			)
			(polygon
				(pts
					(xy 360.10088 -77.669136) (xy 359.59288 -77.669136) (xy 359.59288 -77.288136) (xy 360.10088 -77.288136)
				)
			)
		)
		(zone
			(layer "B.Cu")
			(hatch none 0.5)
			(connect_pads
				(clearance 0)
			)
			(min_thickness 0.25)
			(keepout
				(tracks not_allowed)
				(vias allowed)
				(pads allowed)
				(copperpour not_allowed)
				(footprints allowed)
			)
			(placement
				(enabled no)
				(sheetname "")
			)
			(fill
				(thermal_gap 0.5)
				(thermal_bridge_width 0.5)
				(island_removal_mode 0)
			)
			(polygon
				(pts
					(xy 360.10088 -77.288136) (xy 359.59288 -77.288136) (xy 359.59288 -77.669136) (xy 360.10088 -77.669136)
				)
			)
		)
	)
	(footprint ""
		(layer "B.Cu")
		(at 191.77 -144.4752 180)
		(property "Reference" "C6L7"
			(at 0 0 0)
			(layer "B.SilkS")
			(hide yes)
			(effects
				(font
					(size 1.27 1.27)
				)
				(justify mirror)
			)
		)
		(property "Value" ""
			(at 0 0 0)
			(layer "B.Fab")
			(effects
				(font
					(size 1.27 1.27)
				)
				(justify mirror)
			)
		)
		(duplicate_pad_numbers_are_jumpers no)
		(fp_poly
			(pts
				(xy -0.3048 -0.1016) (xy -0.3048 0.9906) (xy 0.3048 0.9906) (xy 0.3048 -0.1016)
			)
			(stroke
				(width 0)
				(type default)
			)
			(fill no)
			(layer "B.CrtYd")
		)
		(fp_line
			(start 0.3048 0.9906)
			(end -0.3048 0.9906)
			(stroke
				(width 0.1)
				(type default)
			)
			(layer "B.Fab")
		)
		(fp_line
			(start 0.3048 -0.1016)
			(end 0.3048 0.9906)
			(stroke
				(width 0.1)
				(type default)
			)
			(layer "B.Fab")
		)
		(fp_line
			(start -0.3048 0.9906)
			(end -0.3048 -0.1016)
			(stroke
				(width 0.1)
				(type default)
			)
			(layer "B.Fab")
		)
		(fp_line
			(start -0.3048 -0.1016)
			(end 0.3048 -0.1016)
			(stroke
				(width 0.1)
				(type default)
			)
			(layer "B.Fab")
		)
		(pad "1" smd rect
			(at 0 0)
			(size 0.508 0.508)
			(layers "B.Cu" "B.Mask" "B.Paste")
			(net "M_E_CPU_VREF")
		)
		(pad "2" smd rect
			(at 0 0.889)
			(size 0.508 0.508)
			(layers "B.Cu" "B.Mask" "B.Paste")
			(net "GND")
		)
		(zone
			(layer "B.Cu")
			(hatch none 0.5)
			(connect_pads
				(clearance 0)
			)
			(min_thickness 0.25)
			(keepout
				(tracks not_allowed)
				(vias allowed)
				(pads allowed)
				(copperpour not_allowed)
				(footprints allowed)
			)
			(placement
				(enabled no)
				(sheetname "")
			)
			(fill
				(thermal_gap 0.5)
				(thermal_bridge_width 0.5)
				(island_removal_mode 0)
			)
			(polygon
				(pts
					(xy 191.516 -145.1102) (xy 192.024 -145.1102) (xy 192.024 -144.7292) (xy 191.516 -144.7292)
				)
			)
		)
		(zone
			(layer "B.Cu")
			(hatch none 0.5)
			(connect_pads
				(clearance 0)
			)
			(min_thickness 0.25)
			(keepout
				(tracks allowed)
				(vias not_allowed)
				(pads allowed)
				(copperpour not_allowed)
				(footprints allowed)
			)
			(placement
				(enabled no)
				(sheetname "")
			)
			(fill
				(thermal_gap 0.5)
				(thermal_bridge_width 0.5)
				(island_removal_mode 0)
			)
			(polygon
				(pts
					(xy 191.516 -144.7292) (xy 192.024 -144.7292) (xy 192.024 -145.1102) (xy 191.516 -145.1102)
				)
			)
		)
	)
	(footprint ""
		(layer "B.Cu")
		(at 282.0162 -81.6102)
		(property "Reference" "R4P1"
			(at 0 0 0)
			(layer "B.SilkS")
			(hide yes)
			(effects
				(font
					(size 1.27 1.27)
				)
				(justify mirror)
			)
		)
		(property "Value" ""
			(at 0 0 0)
			(layer "B.Fab")
			(effects
				(font
					(size 1.27 1.27)
				)
				(justify mirror)
			)
		)
		(duplicate_pad_numbers_are_jumpers no)
		(fp_poly
			(pts
				(xy 0.2794 -0.1016) (xy -0.2794 -0.1016) (xy -0.2794 0.9906) (xy 0.2794 0.9906)
			)
			(stroke
				(width 0)
				(type default)
			)
			(fill no)
			(layer "B.CrtYd")
		)
		(fp_line
			(start -0.2794 -0.1016)
			(end 0.2794 -0.1016)
			(stroke
				(width 0.1)
				(type default)
			)
			(layer "B.Fab")
		)
		(fp_line
			(start -0.2794 0.9906)
			(end -0.2794 -0.1016)
			(stroke
				(width 0.1)
				(type default)
			)
			(layer "B.Fab")
		)
		(fp_line
			(start 0.2794 -0.1016)
			(end 0.2794 0.9906)
			(stroke
				(width 0.1)
				(type default)
			)
			(layer "B.Fab")
		)
		(fp_line
			(start 0.2794 0.9906)
			(end -0.2794 0.9906)
			(stroke
				(width 0.1)
				(type default)
			)
			(layer "B.Fab")
		)
		(pad "1" smd rect
			(at 0 0 180)
			(size 0.508 0.508)
			(layers "B.Cu" "B.Mask" "B.Paste")
			(net "GND")
		)
		(pad "2" smd rect
			(at 0 0.889 180)
			(size 0.508 0.508)
			(layers "B.Cu" "B.Mask" "B.Paste")
			(net "PD_CPU0_BIST_ENABLE")
		)
		(zone
			(layer "B.Cu")
			(hatch none 0.5)
			(connect_pads
				(clearance 0)
			)
			(min_thickness 0.25)
			(keepout
				(tracks allowed)
				(vias not_allowed)
				(pads allowed)
				(copperpour not_allowed)
				(footprints allowed)
			)
			(placement
				(enabled no)
				(sheetname "")
			)
			(fill
				(thermal_gap 0.5)
				(thermal_bridge_width 0.5)
				(island_removal_mode 0)
			)
			(polygon
				(pts
					(xy 282.2702 -81.3562) (xy 281.7622 -81.3562) (xy 281.7622 -80.9752) (xy 282.2702 -80.9752)
				)
			)
		)
		(zone
			(layer "B.Cu")
			(hatch none 0.5)
			(connect_pads
				(clearance 0)
			)
			(min_thickness 0.25)
			(keepout
				(tracks not_allowed)
				(vias allowed)
				(pads allowed)
				(copperpour not_allowed)
				(footprints allowed)
			)
			(placement
				(enabled no)
				(sheetname "")
			)
			(fill
				(thermal_gap 0.5)
				(thermal_bridge_width 0.5)
				(island_removal_mode 0)
			)
			(polygon
				(pts
					(xy 282.2702 -80.9752) (xy 281.7622 -80.9752) (xy 281.7622 -81.3562) (xy 282.2702 -81.3562)
				)
			)
		)
	)
)
